(kicad_pcb
	(version 20260206)
	(generator "pcbnew")
	(generator_version "10.0")
	(general
		(thickness 1.6)
		(legacy_teardrops no)
	)
	(paper "A4")
	(title_block
		(title "Bryce Canyon_IOM_IOC_16318-2_OCP.brd")
		(comment 1 "Bryce Canyon / footprints 631-637 of 1605")
	)
	(layers
		(0 "F.Cu" signal "TOP")
		(4 "In1.Cu" signal "L2GND")
		(6 "In2.Cu" signal "L3")
		(8 "In3.Cu" signal "L4VCC")
		(10 "In4.Cu" signal "L5VCC")
		(12 "In5.Cu" signal "L6")
		(14 "In6.Cu" signal "L7GND")
		(2 "B.Cu" signal "BOTTOM")
		(9 "F.Adhes" user "F.Adhesive")
		(11 "B.Adhes" user "B.Adhesive")
		(13 "F.Paste" user "Package Geometry/Pastemask Top")
		(15 "B.Paste" user "Package Geometry/Pastemask Bottom")
		(5 "F.SilkS" user "Ref Des/Silkscreen Top")
		(7 "B.SilkS" user "Ref Des/Silkscreen Bottom")
		(1 "F.Mask" user "Board Geometry/Soldermask Top")
		(3 "B.Mask" user "Board Geometry/Soldermask Bottom")
		(17 "Dwgs.User" user "User.Drawings")
		(19 "Cmts.User" user "User.Comments")
		(21 "Eco1.User" user "User.Eco1")
		(23 "Eco2.User" user "User.Eco2")
		(25 "Edge.Cuts" user "Board Geometry/Outline")
		(27 "Margin" user)
		(31 "F.CrtYd" user "Package Geometry/Place Bound Top")
		(29 "B.CrtYd" user "Package Geometry/Place Bound Bottom")
		(35 "F.Fab" user "Ref Des/Assembly Top")
		(33 "B.Fab" user "Ref Des/Assembly Bottom")
	)
	(footprint ""
		(layer "F.Cu")
		(at 174.560738 -68.38442 90)
		(property "Reference" "R585"
			(at 0 0 90)
			(layer "F.SilkS")
			(hide yes)
			(effects
				(font
					(size 1.27 1.27)
				)
			)
		)
		(property "Value" "2K2R2F-GP"
			(at 0.064008 -3.993896 90)
			(unlocked yes)
			(layer "F.Fab")
			(hide yes)
			(effects
				(font
					(size 1.016 1.016)
					(thickness 0.1524)
				)
			)
		)
		(property "Device Type" "R402H16"
			(at 0.064008 -5.517896 90)
			(unlocked yes)
			(layer "F.Fab")
			(hide yes)
			(effects
				(font
					(size 1.016 1.016)
					(thickness 0.1524)
				)
			)
		)
		(duplicate_pad_numbers_are_jumpers no)
		(fp_line
			(start 0.508 -0.9398)
			(end -0.508 -0.9398)
			(stroke
				(width 0.1524)
				(type default)
			)
			(layer "F.SilkS")
		)
		(fp_line
			(start -0.508 -0.9398)
			(end -0.508 0.9398)
			(stroke
				(width 0.1524)
				(type default)
			)
			(layer "F.SilkS")
		)
		(fp_rect
			(start -0.508 0.9398)
			(end 0.508 -0.9398)
			(stroke
				(width 0)
				(type default)
			)
			(fill no)
			(layer "F.CrtYd")
		)
		(fp_rect
			(start -0.508 0.9398)
			(end 0.508 -0.9398)
			(stroke
				(width 0)
				(type default)
			)
			(fill no)
			(layer "F.Fab")
		)
		(pad "1" smd custom
			(at 0 -0.4445 90)
			(size 0.1397 0.1397)
			(layers "F.Cu" "F.Mask" "F.Paste")
			(net "P1V8")
			(options
				(clearance outline)
				(anchor circle)
			)
			(primitives
				(gr_poly
					(pts
						(arc
							(start -0.1778 -0.2794)
							(mid -0.249642 -0.249642)
							(end -0.2794 -0.1778)
						)
						(arc
							(start -0.2794 0.1778)
							(mid -0.249642 0.249642)
							(end -0.1778 0.2794)
						)
						(arc
							(start 0.1778 0.2794)
							(mid 0.249642 0.249642)
							(end 0.2794 0.1778)
						)
						(arc
							(start 0.2794 -0.1778)
							(mid 0.249642 -0.249642)
							(end 0.1778 -0.2794)
						)
					)
					(width 0)
					(fill yes)
				)
			)
		)
		(pad "2" smd custom
			(at 0 0.4445 90)
			(size 0.1397 0.1397)
			(layers "F.Cu" "F.Mask" "F.Paste")
			(net "IOC_SDA_3")
			(options
				(clearance outline)
				(anchor circle)
			)
			(primitives
				(gr_poly
					(pts
						(arc
							(start -0.1778 -0.2794)
							(mid -0.249642 -0.249642)
							(end -0.2794 -0.1778)
						)
						(arc
							(start -0.2794 0.1778)
							(mid -0.249642 0.249642)
							(end -0.1778 0.2794)
						)
						(arc
							(start 0.1778 0.2794)
							(mid 0.249642 0.249642)
							(end 0.2794 0.1778)
						)
						(arc
							(start 0.2794 -0.1778)
							(mid 0.249642 -0.249642)
							(end 0.1778 -0.2794)
						)
					)
					(width 0)
					(fill yes)
				)
			)
		)
	)
	(footprint ""
		(layer "F.Cu")
		(at 154.09164 -134.249922 90)
		(property "Reference" "R520"
			(at 0 0 90)
			(layer "F.SilkS")
			(hide yes)
			(effects
				(font
					(size 1.27 1.27)
				)
			)
		)
		(property "Value" "3D01R5F-GP"
			(at 0 -8.9535 90)
			(unlocked yes)
			(layer "F.Fab")
			(hide yes)
			(effects
				(font
					(size 1.27 1.016)
					(thickness 0.1524)
				)
			)
		)
		(property "Device Type" "R805H24"
			(at 0 -10.6299 90)
			(unlocked yes)
			(layer "F.Fab")
			(hide yes)
			(effects
				(font
					(size 1.27 1.016)
					(thickness 0.1524)
				)
			)
		)
		(duplicate_pad_numbers_are_jumpers no)
		(fp_line
			(start 0.889 -1.7018)
			(end -0.889 -1.7018)
			(stroke
				(width 0.1524)
				(type default)
			)
			(layer "F.SilkS")
		)
		(fp_line
			(start 0.889 -1.7018)
			(end 0.889 -0.381)
			(stroke
				(width 0.1524)
				(type default)
			)
			(layer "F.SilkS")
		)
		(fp_line
			(start -0.889 -1.7018)
			(end -0.889 0.2794)
			(stroke
				(width 0.1524)
				(type default)
			)
			(layer "F.SilkS")
		)
		(fp_line
			(start -0.889 0.0762)
			(end -0.889 1.7018)
			(stroke
				(width 0.1524)
				(type default)
			)
			(layer "F.SilkS")
		)
		(fp_line
			(start 0.889 1.7018)
			(end 0.889 -0.508)
			(stroke
				(width 0.1524)
				(type default)
			)
			(layer "F.SilkS")
		)
		(fp_line
			(start -0.889 1.7018)
			(end 0.889 1.7018)
			(stroke
				(width 0.1524)
				(type default)
			)
			(layer "F.SilkS")
		)
		(fp_poly
			(pts
				(xy 0.9652 -1.778) (xy 0.9652 1.778) (xy -0.9652 1.778) (xy -0.9652 -1.778)
			)
			(stroke
				(width 0)
				(type default)
			)
			(fill no)
			(layer "F.CrtYd")
		)
		(fp_rect
			(start -0.9652 1.778)
			(end 0.9652 -1.778)
			(stroke
				(width 0)
				(type default)
			)
			(fill no)
			(layer "F.Fab")
		)
		(pad "1" smd rect
			(at 0 -0.9652 90)
			(size 1.397 1.143)
			(layers "F.Cu" "F.Mask" "F.Paste")
			(net "P1V8_STBY_SNB")
		)
		(pad "2" smd rect
			(at 0 0.9652 90)
			(size 1.397 1.143)
			(layers "F.Cu" "F.Mask" "F.Paste")
			(net "GND")
		)
	)
	(footprint ""
		(layer "F.Cu")
		(at 190.4746 -48.3616 180)
		(property "Reference" "R640"
			(at 0 0 180)
			(layer "F.SilkS")
			(hide yes)
			(effects
				(font
					(size 1.27 1.27)
				)
			)
		)
		(property "Value" "4K7R2F-GP"
			(at 0.064008 -3.993896 180)
			(unlocked yes)
			(layer "F.Fab")
			(hide yes)
			(effects
				(font
					(size 1.016 1.016)
					(thickness 0.1524)
				)
			)
		)
		(property "Device Type" "R402H16"
			(at 0.064008 -5.517896 180)
			(unlocked yes)
			(layer "F.Fab")
			(hide yes)
			(effects
				(font
					(size 1.016 1.016)
					(thickness 0.1524)
				)
			)
		)
		(duplicate_pad_numbers_are_jumpers no)
		(fp_line
			(start 0.508 -0.9398)
			(end -0.508 -0.9398)
			(stroke
				(width 0.1524)
				(type default)
			)
			(layer "F.SilkS")
		)
		(fp_line
			(start -0.508 -0.9398)
			(end -0.508 0.9398)
			(stroke
				(width 0.1524)
				(type default)
			)
			(layer "F.SilkS")
		)
		(fp_rect
			(start -0.508 0.9398)
			(end 0.508 -0.9398)
			(stroke
				(width 0)
				(type default)
			)
			(fill no)
			(layer "F.CrtYd")
		)
		(fp_rect
			(start -0.508 0.9398)
			(end 0.508 -0.9398)
			(stroke
				(width 0)
				(type default)
			)
			(fill no)
			(layer "F.Fab")
		)
		(pad "1" smd custom
			(at 0 -0.4445 180)
			(size 0.1397 0.1397)
			(layers "F.Cu" "F.Mask" "F.Paste")
			(net "P1V8")
			(options
				(clearance outline)
				(anchor circle)
			)
			(primitives
				(gr_poly
					(pts
						(arc
							(start -0.1778 -0.2794)
							(mid -0.249642 -0.249642)
							(end -0.2794 -0.1778)
						)
						(arc
							(start -0.2794 0.1778)
							(mid -0.249642 0.249642)
							(end -0.1778 0.2794)
						)
						(arc
							(start 0.1778 0.2794)
							(mid 0.249642 0.249642)
							(end 0.2794 0.1778)
						)
						(arc
							(start 0.2794 -0.1778)
							(mid 0.249642 -0.249642)
							(end 0.1778 -0.2794)
						)
					)
					(width 0)
					(fill yes)
				)
			)
		)
		(pad "2" smd custom
			(at 0 0.4445 180)
			(size 0.1397 0.1397)
			(layers "F.Cu" "F.Mask" "F.Paste")
			(net "LSI_SCAN_EN")
			(options
				(clearance outline)
				(anchor circle)
			)
			(primitives
				(gr_poly
					(pts
						(arc
							(start -0.1778 -0.2794)
							(mid -0.249642 -0.249642)
							(end -0.2794 -0.1778)
						)
						(arc
							(start -0.2794 0.1778)
							(mid -0.249642 0.249642)
							(end -0.1778 0.2794)
						)
						(arc
							(start 0.1778 0.2794)
							(mid 0.249642 0.249642)
							(end 0.2794 0.1778)
						)
						(arc
							(start 0.2794 -0.1778)
							(mid 0.249642 -0.249642)
							(end 0.1778 -0.2794)
						)
					)
					(width 0)
					(fill yes)
				)
			)
		)
	)
	(footprint ""
		(layer "F.Cu")
		(at 94.765876 -20.34413 90)
		(property "Reference" "D16"
			(at 0 0 90)
			(layer "F.SilkS")
			(hide yes)
			(effects
				(font
					(size 1.27 1.27)
				)
			)
		)
		(property "Value" "PESD5V0S1BL-1-GP"
			(at 1.8923 -1.5621 90)
			(unlocked yes)
			(layer "F.Fab")
			(hide yes)
			(effects
				(font
					(size 1.016 1.016)
					(thickness 0.1524)
				)
			)
		)
		(property "Device Type" "SOD882-10D6-1H20"
			(at 1.8923 -3.0861 90)
			(unlocked yes)
			(layer "F.Fab")
			(hide yes)
			(effects
				(font
					(size 1.016 1.016)
					(thickness 0.1524)
				)
			)
		)
		(duplicate_pad_numbers_are_jumpers no)
		(fp_line
			(start -0.3048 -0.9271)
			(end 0.3048 -0.9271)
			(stroke
				(width 0.254)
				(type default)
			)
			(layer "F.SilkS")
		)
		(fp_rect
			(start -0.2921 0.4953)
			(end 0.2921 -0.4953)
			(stroke
				(width 0)
				(type default)
			)
			(fill no)
			(layer "F.CrtYd")
		)
		(fp_poly
			(pts
				(xy -0.4318 0.8001) (xy -0.4318 -0.266192) (xy -0.2921 -0.266192) (xy -0.2921 0.4953) (xy 0.2921 0.4953)
				(xy 0.2921 -0.4953) (xy -0.2921 -0.4953) (xy -0.2921 -0.2667) (xy -0.4318 -0.2667) (xy -0.4318 -0.8001)
				(xy 0.4318 -0.8001) (xy 0.4318 0.8001)
			)
			(stroke
				(width 0)
				(type default)
			)
			(fill no)
			(layer "F.CrtYd")
		)
		(fp_rect
			(start -0.4318 0.8001)
			(end 0.4318 -0.8001)
			(stroke
				(width 0)
				(type default)
			)
			(fill no)
			(layer "F.Fab")
		)
		(pad "1" smd custom
			(at 0 -0.4445 90)
			(size 0.1143 0.1143)
			(layers "F.Cu" "F.Mask" "F.Paste")
			(net "UART_IOM_TX")
			(options
				(clearance outline)
				(anchor circle)
			)
			(primitives
				(gr_poly
					(pts
						(arc
							(start -0.2032 0.2286)
							(mid -0.275042 0.198842)
							(end -0.3048 0.127)
						)
						(arc
							(start -0.3048 -0.127)
							(mid -0.275042 -0.198842)
							(end -0.2032 -0.2286)
						)
						(arc
							(start 0.2032 -0.2286)
							(mid 0.275042 -0.198842)
							(end 0.3048 -0.127)
						)
						(arc
							(start 0.3048 0.127)
							(mid 0.275042 0.198842)
							(end 0.2032 0.2286)
						)
					)
					(width 0)
					(fill yes)
				)
			)
		)
		(pad "2" smd custom
			(at 0 0.4445 90)
			(size 0.1143 0.1143)
			(layers "F.Cu" "F.Mask" "F.Paste")
			(net "GND")
			(options
				(clearance outline)
				(anchor circle)
			)
			(primitives
				(gr_poly
					(pts
						(arc
							(start 0.2032 -0.2286)
							(mid 0.275042 -0.198842)
							(end 0.3048 -0.127)
						)
						(arc
							(start 0.3048 0.127)
							(mid 0.275042 0.198842)
							(end 0.2032 0.2286)
						)
						(arc
							(start -0.2032 0.2286)
							(mid -0.275042 0.198842)
							(end -0.3048 0.127)
						)
						(arc
							(start -0.3048 -0.127)
							(mid -0.275042 -0.198842)
							(end -0.2032 -0.2286)
						)
					)
					(width 0)
					(fill yes)
				)
			)
		)
	)
	(footprint ""
		(layer "F.Cu")
		(at 110.71479 -9.666478 -90)
		(property "Reference" "R454"
			(at 0 0 270)
			(layer "F.SilkS")
			(hide yes)
			(effects
				(font
					(size 1.27 1.27)
				)
			)
		)
		(property "Value" "51KR2F-L-GP"
			(at 0.064008 -3.993896 270)
			(unlocked yes)
			(layer "F.Fab")
			(hide yes)
			(effects
				(font
					(size 1.016 1.016)
					(thickness 0.1524)
				)
			)
		)
		(property "Device Type" "R402H16"
			(at 0.064008 -5.517896 270)
			(unlocked yes)
			(layer "F.Fab")
			(hide yes)
			(effects
				(font
					(size 1.016 1.016)
					(thickness 0.1524)
				)
			)
		)
		(duplicate_pad_numbers_are_jumpers no)
		(fp_line
			(start -0.508 -0.9398)
			(end -0.508 0.9398)
			(stroke
				(width 0.1524)
				(type default)
			)
			(layer "F.SilkS")
		)
		(fp_line
			(start 0.508 -0.9398)
			(end -0.508 -0.9398)
			(stroke
				(width 0.1524)
				(type default)
			)
			(layer "F.SilkS")
		)
		(fp_rect
			(start -0.508 0.9398)
			(end 0.508 -0.9398)
			(stroke
				(width 0)
				(type default)
			)
			(fill no)
			(layer "F.CrtYd")
		)
		(fp_rect
			(start -0.508 0.9398)
			(end 0.508 -0.9398)
			(stroke
				(width 0)
				(type default)
			)
			(fill no)
			(layer "F.Fab")
		)
		(pad "1" smd custom
			(at 0 -0.4445 270)
			(size 0.1397 0.1397)
			(layers "F.Cu" "F.Mask" "F.Paste")
			(net "MB0_ISET_R")
			(options
				(clearance outline)
				(anchor circle)
			)
			(primitives
				(gr_poly
					(pts
						(arc
							(start -0.1778 -0.2794)
							(mid -0.249642 -0.249642)
							(end -0.2794 -0.1778)
						)
						(arc
							(start -0.2794 0.1778)
							(mid -0.249642 0.249642)
							(end -0.1778 0.2794)
						)
						(arc
							(start 0.1778 0.2794)
							(mid 0.249642 0.249642)
							(end 0.2794 0.1778)
						)
						(arc
							(start 0.2794 -0.1778)
							(mid 0.249642 -0.249642)
							(end 0.1778 -0.2794)
						)
					)
					(width 0)
					(fill yes)
				)
			)
		)
		(pad "2" smd custom
			(at 0 0.4445 270)
			(size 0.1397 0.1397)
			(layers "F.Cu" "F.Mask" "F.Paste")
			(net "AGND_CURRENT_MON")
			(options
				(clearance outline)
				(anchor circle)
			)
			(primitives
				(gr_poly
					(pts
						(arc
							(start -0.1778 -0.2794)
							(mid -0.249642 -0.249642)
							(end -0.2794 -0.1778)
						)
						(arc
							(start -0.2794 0.1778)
							(mid -0.249642 0.249642)
							(end -0.1778 0.2794)
						)
						(arc
							(start 0.1778 0.2794)
							(mid 0.249642 0.249642)
							(end 0.2794 0.1778)
						)
						(arc
							(start 0.2794 -0.1778)
							(mid 0.249642 -0.249642)
							(end 0.1778 -0.2794)
						)
					)
					(width 0)
					(fill yes)
				)
			)
		)
	)
	(footprint ""
		(layer "F.Cu")
		(at 76.484226 -140.627862 -90)
		(property "Reference" "C135"
			(at 0 0 270)
			(layer "F.SilkS")
			(hide yes)
			(effects
				(font
					(size 1.27 1.27)
				)
			)
		)
		(property "Value" "SCD1U16V2KX-3GP"
			(at 1.1811 -2.7051 270)
			(unlocked yes)
			(layer "F.Fab")
			(hide yes)
			(effects
				(font
					(size 1.016 1.016)
					(thickness 0.1524)
				)
			)
		)
		(property "Device Type" "C402H22"
			(at 1.1811 -4.2291 270)
			(unlocked yes)
			(layer "F.Fab")
			(hide yes)
			(effects
				(font
					(size 1.016 1.016)
					(thickness 0.1524)
				)
			)
		)
		(duplicate_pad_numbers_are_jumpers no)
		(fp_rect
			(start -0.4318 0.9525)
			(end 0.4318 -0.9525)
			(stroke
				(width 0)
				(type default)
			)
			(fill no)
			(layer "F.CrtYd")
		)
		(fp_rect
			(start -0.4318 0.9525)
			(end 0.4318 -0.9525)
			(stroke
				(width 0)
				(type default)
			)
			(fill no)
			(layer "F.Fab")
		)
		(pad "1" smd custom
			(at 0 -0.4445 270)
			(size 0.1524 0.1524)
			(layers "F.Cu" "F.Mask" "F.Paste")
			(net "P3V3_STBY")
			(options
				(clearance outline)
				(anchor circle)
			)
			(primitives
				(gr_poly
					(pts
						(arc
							(start 0.3048 -0.2032)
							(mid 0.275042 -0.275042)
							(end 0.2032 -0.3048)
						)
						(arc
							(start -0.2032 -0.3048)
							(mid -0.275042 -0.275042)
							(end -0.3048 -0.2032)
						)
						(arc
							(start -0.3048 0.2032)
							(mid -0.275042 0.275042)
							(end -0.2032 0.3048)
						)
						(arc
							(start 0.2032 0.3048)
							(mid 0.275042 0.275042)
							(end 0.3048 0.2032)
						)
					)
					(width 0)
					(fill yes)
				)
			)
		)
		(pad "2" smd custom
			(at 0 0.4445 270)
			(size 0.1524 0.1524)
			(layers "F.Cu" "F.Mask" "F.Paste")
			(net "GND")
			(options
				(clearance outline)
				(anchor circle)
			)
			(primitives
				(gr_poly
					(pts
						(arc
							(start 0.3048 -0.2032)
							(mid 0.275042 -0.275042)
							(end 0.2032 -0.3048)
						)
						(arc
							(start -0.2032 -0.3048)
							(mid -0.275042 -0.275042)
							(end -0.3048 -0.2032)
						)
						(arc
							(start -0.3048 0.2032)
							(mid -0.275042 0.275042)
							(end -0.2032 0.3048)
						)
						(arc
							(start 0.2032 0.3048)
							(mid 0.275042 0.275042)
							(end 0.3048 0.2032)
						)
					)
					(width 0)
					(fill yes)
				)
			)
		)
	)
	(footprint ""
		(layer "F.Cu")
		(at 34.5694 -165.0238 180)
		(property "Reference" "R699"
			(at 0 0 180)
			(layer "F.SilkS")
			(hide yes)
			(effects
				(font
					(size 1.27 1.27)
				)
			)
		)
		(property "Value" "4K7R2F-GP"
			(at 0.064008 -3.993896 180)
			(unlocked yes)
			(layer "F.Fab")
			(hide yes)
			(effects
				(font
					(size 1.016 1.016)
					(thickness 0.1524)
				)
			)
		)
		(property "Device Type" "R402H16"
			(at 0.064008 -5.517896 180)
			(unlocked yes)
			(layer "F.Fab")
			(hide yes)
			(effects
				(font
					(size 1.016 1.016)
					(thickness 0.1524)
				)
			)
		)
		(duplicate_pad_numbers_are_jumpers no)
		(fp_line
			(start 0.508 -0.9398)
			(end -0.508 -0.9398)
			(stroke
				(width 0.1524)
				(type default)
			)
			(layer "F.SilkS")
		)
		(fp_line
			(start -0.508 -0.9398)
			(end -0.508 0.9398)
			(stroke
				(width 0.1524)
				(type default)
			)
			(layer "F.SilkS")
		)
		(fp_rect
			(start -0.508 0.9398)
			(end 0.508 -0.9398)
			(stroke
				(width 0)
				(type default)
			)
			(fill no)
			(layer "F.CrtYd")
		)
		(fp_rect
			(start -0.508 0.9398)
			(end 0.508 -0.9398)
			(stroke
				(width 0)
				(type default)
			)
			(fill no)
			(layer "F.Fab")
		)
		(pad "1" smd custom
			(at 0 -0.4445 180)
			(size 0.1397 0.1397)
			(layers "F.Cu" "F.Mask" "F.Paste")
			(net "IOM_TYPE2")
			(options
				(clearance outline)
				(anchor circle)
			)
			(primitives
				(gr_poly
					(pts
						(arc
							(start -0.1778 -0.2794)
							(mid -0.249642 -0.249642)
							(end -0.2794 -0.1778)
						)
						(arc
							(start -0.2794 0.1778)
							(mid -0.249642 0.249642)
							(end -0.1778 0.2794)
						)
						(arc
							(start 0.1778 0.2794)
							(mid 0.249642 0.249642)
							(end 0.2794 0.1778)
						)
						(arc
							(start 0.2794 -0.1778)
							(mid 0.249642 -0.249642)
							(end 0.1778 -0.2794)
						)
					)
					(width 0)
					(fill yes)
				)
			)
		)
		(pad "2" smd custom
			(at 0 0.4445 180)
			(size 0.1397 0.1397)
			(layers "F.Cu" "F.Mask" "F.Paste")
			(net "GND")
			(options
				(clearance outline)
				(anchor circle)
			)
			(primitives
				(gr_poly
					(pts
						(arc
							(start -0.1778 -0.2794)
							(mid -0.249642 -0.249642)
							(end -0.2794 -0.1778)
						)
						(arc
							(start -0.2794 0.1778)
							(mid -0.249642 0.249642)
							(end -0.1778 0.2794)
						)
						(arc
							(start 0.1778 0.2794)
							(mid 0.249642 0.249642)
							(end 0.2794 0.1778)
						)
						(arc
							(start 0.2794 -0.1778)
							(mid 0.249642 -0.249642)
							(end 0.1778 -0.2794)
						)
					)
					(width 0)
					(fill yes)
				)
			)
		)
	)
)
